(kicad_pcb
	(version 20260206)
	(generator "pcbnew")
	(generator_version "10.0")
	(general
		(thickness 1.6)
		(legacy_teardrops no)
	)
	(paper "A4")
	(title_block
		(title "v2-tray-backplane — ms_tbp_v2.brd")
		(comment 1 "Open CloudServer (Microsoft) / footprint 17 of 164 (J14), pads 1-121 of 162")
	)
	(layers
		(0 "F.Cu" signal "TOP")
		(4 "In1.Cu" signal "LYR2")
		(6 "In2.Cu" signal "LYR3")
		(8 "In3.Cu" signal "LYR4")
		(10 "In4.Cu" signal "LYR5")
		(12 "In5.Cu" signal "LYR6")
		(14 "In6.Cu" signal "LYR7")
		(2 "B.Cu" signal "BOTTOM")
		(9 "F.Adhes" user "F.Adhesive")
		(11 "B.Adhes" user "B.Adhesive")
		(13 "F.Paste" user "Package Geometry/Pastemask Top")
		(15 "B.Paste" user "Package Geometry/Pastemask Bottom")
		(5 "F.SilkS" user "Ref Des/Silkscreen Top")
		(7 "B.SilkS" user "Ref Des/Silkscreen Bottom")
		(1 "F.Mask" user "Board Geometry/Soldermask Top")
		(3 "B.Mask" user "Board Geometry/Soldermask Bottom")
		(17 "Dwgs.User" user "User.Drawings")
		(19 "Cmts.User" user "User.Comments")
		(21 "Eco1.User" user "User.Eco1")
		(23 "Eco2.User" user "User.Eco2")
		(25 "Edge.Cuts" user "Board Geometry/Outline")
		(27 "Margin" user)
		(31 "F.CrtYd" user "Package Geometry/Place Bound Top")
		(29 "B.CrtYd" user "Package Geometry/Place Bound Bottom")
		(35 "F.Fab" user "Ref Des/Assembly Top")
		(33 "B.Fab" user "Ref Des/Assembly Bottom")
	)
	(footprint ""
		(layer "F.Cu")
		(at -154.079999 30.959999 90)
		(property "Reference" "J14"
			(at 17.078899 0.028999 0)
			(unlocked yes)
			(layer "F.SilkS")
			(effects
				(font
					(size 0.762 0.5334)
					(thickness 0.1016)
				)
			)
		)
		(property "Value" ""
			(at 0 0 90)
			(layer "F.Fab")
			(effects
				(font
					(size 1.27 1.27)
				)
			)
		)
		(duplicate_pad_numbers_are_jumpers no)
		(pad "" np_thru_hole circle
			(at -14.4907 -3.048 90)
			(size 0.508 0.508)
			(drill 1.27)
			(layers "*.Cu" "*.Mask")
		)
		(pad "" np_thru_hole circle
			(at 14.4907 0 90)
			(size 0.508 0.508)
			(drill 1.27)
			(layers "*.Cu" "*.Mask")
		)
		(pad "1" smd circle
			(at -12.065 -4.445 90)
			(size 0.635 0.635)
			(layers "F.Cu" "F.Mask" "F.Paste")
			(net "GND")
		)
		(pad "2" smd circle
			(at -12.065 -3.175 90)
			(size 0.635 0.635)
			(layers "F.Cu" "F.Mask" "F.Paste")
			(net "PCIE_T2B_B2_RX_DP<7>")
		)
		(pad "3" smd circle
			(at -12.065 -1.905 90)
			(size 0.635 0.635)
			(layers "F.Cu" "F.Mask" "F.Paste")
			(net "GND")
		)
		(pad "4" smd circle
			(at -12.065 -0.635 90)
			(size 0.635 0.635)
			(layers "F.Cu" "F.Mask" "F.Paste")
			(net "PCIE_T2B_B2_RX_DP<15>")
		)
		(pad "5" smd circle
			(at -12.065 0.635 90)
			(size 0.635 0.635)
			(layers "F.Cu" "F.Mask" "F.Paste")
			(net "GND")
		)
		(pad "6" smd circle
			(at -12.065 1.905 90)
			(size 0.635 0.635)
			(layers "F.Cu" "F.Mask" "F.Paste")
			(net "PCIE_B2T_B2_TX_DP<7>")
		)
		(pad "7" smd circle
			(at -12.065 3.175 90)
			(size 0.635 0.635)
			(layers "F.Cu" "F.Mask" "F.Paste")
			(net "GND")
		)
		(pad "8" smd circle
			(at -12.065 4.445 90)
			(size 0.635 0.635)
			(layers "F.Cu" "F.Mask" "F.Paste")
			(net "PCIE_B2T_B2_TX_DP<15>")
		)
		(pad "9" smd circle
			(at -10.795 -4.445 90)
			(size 0.635 0.635)
			(layers "F.Cu" "F.Mask" "F.Paste")
			(net "GND")
		)
		(pad "10" smd circle
			(at -10.795 -3.175 90)
			(size 0.635 0.635)
			(layers "F.Cu" "F.Mask" "F.Paste")
			(net "PCIE_T2B_B2_RX_DN<7>")
		)
		(pad "11" smd circle
			(at -10.795 -1.905 90)
			(size 0.635 0.635)
			(layers "F.Cu" "F.Mask" "F.Paste")
			(net "GND")
		)
		(pad "12" smd circle
			(at -10.795 -0.635 90)
			(size 0.635 0.635)
			(layers "F.Cu" "F.Mask" "F.Paste")
			(net "PCIE_T2B_B2_RX_DN<15>")
		)
		(pad "13" smd circle
			(at -10.795 0.635 90)
			(size 0.635 0.635)
			(layers "F.Cu" "F.Mask" "F.Paste")
			(net "GND")
		)
		(pad "14" smd circle
			(at -10.795 1.905 90)
			(size 0.635 0.635)
			(layers "F.Cu" "F.Mask" "F.Paste")
			(net "PCIE_B2T_B2_TX_DN<7>")
		)
		(pad "15" smd circle
			(at -10.795 3.175 90)
			(size 0.635 0.635)
			(layers "F.Cu" "F.Mask" "F.Paste")
			(net "GND")
		)
		(pad "16" smd circle
			(at -10.795 4.445 90)
			(size 0.635 0.635)
			(layers "F.Cu" "F.Mask" "F.Paste")
			(net "PCIE_B2T_B2_TX_DN<15>")
		)
		(pad "17" smd circle
			(at -9.525 -4.445 90)
			(size 0.635 0.635)
			(layers "F.Cu" "F.Mask" "F.Paste")
			(net "PCIE_T2B_B2_RX_DP<6>")
		)
		(pad "18" smd circle
			(at -9.525 -3.175 90)
			(size 0.635 0.635)
			(layers "F.Cu" "F.Mask" "F.Paste")
			(net "GND")
		)
		(pad "19" smd circle
			(at -9.525 -1.905 90)
			(size 0.635 0.635)
			(layers "F.Cu" "F.Mask" "F.Paste")
			(net "PCIE_T2B_B2_RX_DP<14>")
		)
		(pad "20" smd circle
			(at -9.525 -0.635 90)
			(size 0.635 0.635)
			(layers "F.Cu" "F.Mask" "F.Paste")
			(net "GND")
		)
		(pad "21" smd circle
			(at -9.525 0.635 90)
			(size 0.635 0.635)
			(layers "F.Cu" "F.Mask" "F.Paste")
			(net "PCIE_B2T_B2_TX_DP<6>")
		)
		(pad "22" smd circle
			(at -9.525 1.905 90)
			(size 0.635 0.635)
			(layers "F.Cu" "F.Mask" "F.Paste")
			(net "GND")
		)
		(pad "23" smd circle
			(at -9.525 3.175 90)
			(size 0.635 0.635)
			(layers "F.Cu" "F.Mask" "F.Paste")
			(net "PCIE_B2T_B2_TX_DP<14>")
		)
		(pad "24" smd circle
			(at -9.525 4.445 90)
			(size 0.635 0.635)
			(layers "F.Cu" "F.Mask" "F.Paste")
			(net "GND")
		)
		(pad "25" smd circle
			(at -8.255 -4.445 90)
			(size 0.635 0.635)
			(layers "F.Cu" "F.Mask" "F.Paste")
			(net "PCIE_T2B_B2_RX_DN<6>")
		)
		(pad "26" smd circle
			(at -8.255 -3.175 90)
			(size 0.635 0.635)
			(layers "F.Cu" "F.Mask" "F.Paste")
			(net "GND")
		)
		(pad "27" smd circle
			(at -8.255 -1.905 90)
			(size 0.635 0.635)
			(layers "F.Cu" "F.Mask" "F.Paste")
			(net "PCIE_T2B_B2_RX_DN<14>")
		)
		(pad "28" smd circle
			(at -8.255 -0.635 90)
			(size 0.635 0.635)
			(layers "F.Cu" "F.Mask" "F.Paste")
			(net "GND")
		)
		(pad "29" smd circle
			(at -8.255 0.635 90)
			(size 0.635 0.635)
			(layers "F.Cu" "F.Mask" "F.Paste")
			(net "PCIE_B2T_B2_TX_DN<6>")
		)
		(pad "30" smd circle
			(at -8.255 1.905 90)
			(size 0.635 0.635)
			(layers "F.Cu" "F.Mask" "F.Paste")
			(net "GND")
		)
		(pad "31" smd circle
			(at -8.255 3.175 90)
			(size 0.635 0.635)
			(layers "F.Cu" "F.Mask" "F.Paste")
			(net "PCIE_B2T_B2_TX_DN<14>")
		)
		(pad "32" smd circle
			(at -8.255 4.445 90)
			(size 0.635 0.635)
			(layers "F.Cu" "F.Mask" "F.Paste")
			(net "GND")
		)
		(pad "33" smd circle
			(at -6.985 -4.445 90)
			(size 0.635 0.635)
			(layers "F.Cu" "F.Mask" "F.Paste")
			(net "GND")
		)
		(pad "34" smd circle
			(at -6.985 -3.175 90)
			(size 0.635 0.635)
			(layers "F.Cu" "F.Mask" "F.Paste")
			(net "PCIE_T2B_B2_RX_DP<5>")
		)
		(pad "35" smd circle
			(at -6.985 -1.905 90)
			(size 0.635 0.635)
			(layers "F.Cu" "F.Mask" "F.Paste")
			(net "GND")
		)
		(pad "36" smd circle
			(at -6.985 -0.635 90)
			(size 0.635 0.635)
			(layers "F.Cu" "F.Mask" "F.Paste")
			(net "PCIE_T2B_B2_RX_DP<13>")
		)
		(pad "37" smd circle
			(at -6.985 0.635 90)
			(size 0.635 0.635)
			(layers "F.Cu" "F.Mask" "F.Paste")
			(net "GND")
		)
		(pad "38" smd circle
			(at -6.985 1.905 90)
			(size 0.635 0.635)
			(layers "F.Cu" "F.Mask" "F.Paste")
			(net "PCIE_B2T_B2_TX_DP<5>")
		)
		(pad "39" smd circle
			(at -6.985 3.175 90)
			(size 0.635 0.635)
			(layers "F.Cu" "F.Mask" "F.Paste")
			(net "GND")
		)
		(pad "40" smd circle
			(at -6.985 4.445 90)
			(size 0.635 0.635)
			(layers "F.Cu" "F.Mask" "F.Paste")
			(net "PCIE_B2T_B2_TX_DP<13>")
		)
		(pad "41" smd circle
			(at -5.715 -4.445 90)
			(size 0.635 0.635)
			(layers "F.Cu" "F.Mask" "F.Paste")
			(net "GND")
		)
		(pad "42" smd circle
			(at -5.715 -3.175 90)
			(size 0.635 0.635)
			(layers "F.Cu" "F.Mask" "F.Paste")
			(net "PCIE_T2B_B2_RX_DN<5>")
		)
		(pad "43" smd circle
			(at -5.715 -1.905 90)
			(size 0.635 0.635)
			(layers "F.Cu" "F.Mask" "F.Paste")
			(net "GND")
		)
		(pad "44" smd circle
			(at -5.715 -0.635 90)
			(size 0.635 0.635)
			(layers "F.Cu" "F.Mask" "F.Paste")
			(net "PCIE_T2B_B2_RX_DN<13>")
		)
		(pad "45" smd circle
			(at -5.715 0.635 90)
			(size 0.635 0.635)
			(layers "F.Cu" "F.Mask" "F.Paste")
			(net "GND")
		)
		(pad "46" smd circle
			(at -5.715 1.905 90)
			(size 0.635 0.635)
			(layers "F.Cu" "F.Mask" "F.Paste")
			(net "PCIE_B2T_B2_TX_DN<5>")
		)
		(pad "47" smd circle
			(at -5.715 3.175 90)
			(size 0.635 0.635)
			(layers "F.Cu" "F.Mask" "F.Paste")
			(net "GND")
		)
		(pad "48" smd circle
			(at -5.715 4.445 90)
			(size 0.635 0.635)
			(layers "F.Cu" "F.Mask" "F.Paste")
			(net "PCIE_B2T_B2_TX_DN<13>")
		)
		(pad "49" smd circle
			(at -4.445 -4.445 90)
			(size 0.635 0.635)
			(layers "F.Cu" "F.Mask" "F.Paste")
			(net "PCIE_T2B_B2_RX_DP<4>")
		)
		(pad "50" smd circle
			(at -4.445 -3.175 90)
			(size 0.635 0.635)
			(layers "F.Cu" "F.Mask" "F.Paste")
			(net "GND")
		)
		(pad "51" smd circle
			(at -4.445 -1.905 90)
			(size 0.635 0.635)
			(layers "F.Cu" "F.Mask" "F.Paste")
			(net "PCIE_T2B_B2_RX_DP<12>")
		)
		(pad "52" smd circle
			(at -4.445 -0.635 90)
			(size 0.635 0.635)
			(layers "F.Cu" "F.Mask" "F.Paste")
			(net "GND")
		)
		(pad "53" smd circle
			(at -4.445 0.635 90)
			(size 0.635 0.635)
			(layers "F.Cu" "F.Mask" "F.Paste")
			(net "PCIE_B2T_B2_TX_DP<4>")
		)
		(pad "54" smd circle
			(at -4.445 1.905 90)
			(size 0.635 0.635)
			(layers "F.Cu" "F.Mask" "F.Paste")
			(net "GND")
		)
		(pad "55" smd circle
			(at -4.445 3.175 90)
			(size 0.635 0.635)
			(layers "F.Cu" "F.Mask" "F.Paste")
			(net "PCIE_B2T_B2_TX_DP<12>")
		)
		(pad "56" smd circle
			(at -4.445 4.445 90)
			(size 0.635 0.635)
			(layers "F.Cu" "F.Mask" "F.Paste")
			(net "GND")
		)
		(pad "57" smd circle
			(at -3.175 -4.445 90)
			(size 0.635 0.635)
			(layers "F.Cu" "F.Mask" "F.Paste")
			(net "PCIE_T2B_B2_RX_DN<4>")
		)
		(pad "58" smd circle
			(at -3.175 -3.175 90)
			(size 0.635 0.635)
			(layers "F.Cu" "F.Mask" "F.Paste")
			(net "GND")
		)
		(pad "59" smd circle
			(at -3.175 -1.905 90)
			(size 0.635 0.635)
			(layers "F.Cu" "F.Mask" "F.Paste")
			(net "PCIE_T2B_B2_RX_DN<12>")
		)
		(pad "60" smd circle
			(at -3.175 -0.635 90)
			(size 0.635 0.635)
			(layers "F.Cu" "F.Mask" "F.Paste")
			(net "GND")
		)
		(pad "61" smd circle
			(at -3.175 0.635 90)
			(size 0.635 0.635)
			(layers "F.Cu" "F.Mask" "F.Paste")
			(net "PCIE_B2T_B2_TX_DN<4>")
		)
		(pad "62" smd circle
			(at -3.175 1.905 90)
			(size 0.635 0.635)
			(layers "F.Cu" "F.Mask" "F.Paste")
			(net "GND")
		)
		(pad "63" smd circle
			(at -3.175 3.175 90)
			(size 0.635 0.635)
			(layers "F.Cu" "F.Mask" "F.Paste")
			(net "PCIE_B2T_B2_TX_DN<12>")
		)
		(pad "64" smd circle
			(at -3.175 4.445 90)
			(size 0.635 0.635)
			(layers "F.Cu" "F.Mask" "F.Paste")
			(net "GND")
		)
		(pad "65" smd circle
			(at -1.905 -4.445 90)
			(size 0.635 0.635)
			(layers "F.Cu" "F.Mask" "F.Paste")
			(net "GND")
		)
		(pad "66" smd circle
			(at -1.905 -3.175 90)
			(size 0.635 0.635)
			(layers "F.Cu" "F.Mask" "F.Paste")
			(net "PCIE_T2B_B2_RX_DP<3>")
		)
		(pad "67" smd circle
			(at -1.905 -1.905 90)
			(size 0.635 0.635)
			(layers "F.Cu" "F.Mask" "F.Paste")
			(net "GND")
		)
		(pad "68" smd circle
			(at -1.905 -0.635 90)
			(size 0.635 0.635)
			(layers "F.Cu" "F.Mask" "F.Paste")
			(net "PCIE_T2B_B2_RX_DP<11>")
		)
		(pad "69" smd circle
			(at -1.905 0.635 90)
			(size 0.635 0.635)
			(layers "F.Cu" "F.Mask" "F.Paste")
			(net "GND")
		)
		(pad "70" smd circle
			(at -1.905 1.905 90)
			(size 0.635 0.635)
			(layers "F.Cu" "F.Mask" "F.Paste")
			(net "PCIE_B2T_B2_TX_DP<3>")
		)
		(pad "71" smd circle
			(at -1.905 3.175 90)
			(size 0.635 0.635)
			(layers "F.Cu" "F.Mask" "F.Paste")
			(net "GND")
		)
		(pad "72" smd circle
			(at -1.905 4.445 90)
			(size 0.635 0.635)
			(layers "F.Cu" "F.Mask" "F.Paste")
			(net "PCIE_B2T_B2_TX_DP<11>")
		)
		(pad "73" smd circle
			(at -0.635 -4.445 90)
			(size 0.635 0.635)
			(layers "F.Cu" "F.Mask" "F.Paste")
			(net "GND")
		)
		(pad "74" smd circle
			(at -0.635 -3.175 90)
			(size 0.635 0.635)
			(layers "F.Cu" "F.Mask" "F.Paste")
			(net "PCIE_T2B_B2_RX_DN<3>")
		)
		(pad "75" smd circle
			(at -0.635 -1.905 90)
			(size 0.635 0.635)
			(layers "F.Cu" "F.Mask" "F.Paste")
			(net "GND")
		)
		(pad "76" smd circle
			(at -0.635 -0.635 90)
			(size 0.635 0.635)
			(layers "F.Cu" "F.Mask" "F.Paste")
			(net "PCIE_T2B_B2_RX_DN<11>")
		)
		(pad "77" smd circle
			(at -0.635 0.635 90)
			(size 0.635 0.635)
			(layers "F.Cu" "F.Mask" "F.Paste")
			(net "GND")
		)
		(pad "78" smd circle
			(at -0.635 1.905 90)
			(size 0.635 0.635)
			(layers "F.Cu" "F.Mask" "F.Paste")
			(net "PCIE_B2T_B2_TX_DN<3>")
		)
		(pad "79" smd circle
			(at -0.635 3.175 90)
			(size 0.635 0.635)
			(layers "F.Cu" "F.Mask" "F.Paste")
			(net "GND")
		)
		(pad "80" smd circle
			(at -0.635 4.445 90)
			(size 0.635 0.635)
			(layers "F.Cu" "F.Mask" "F.Paste")
			(net "PCIE_B2T_B2_TX_DN<11>")
		)
		(pad "81" smd circle
			(at 0.635 -4.445 90)
			(size 0.635 0.635)
			(layers "F.Cu" "F.Mask" "F.Paste")
			(net "PCIE_T2B_B2_RX_DP<2>")
		)
		(pad "82" smd circle
			(at 0.635 -3.175 90)
			(size 0.635 0.635)
			(layers "F.Cu" "F.Mask" "F.Paste")
			(net "GND")
		)
		(pad "83" smd circle
			(at 0.635 -1.905 90)
			(size 0.635 0.635)
			(layers "F.Cu" "F.Mask" "F.Paste")
			(net "PCIE_T2B_B2_RX_DP<10>")
		)
		(pad "84" smd circle
			(at 0.635 -0.635 90)
			(size 0.635 0.635)
			(layers "F.Cu" "F.Mask" "F.Paste")
			(net "GND")
		)
		(pad "85" smd circle
			(at 0.635 0.635 90)
			(size 0.635 0.635)
			(layers "F.Cu" "F.Mask" "F.Paste")
			(net "PCIE_B2T_B2_TX_DP<2>")
		)
		(pad "86" smd circle
			(at 0.635 1.905 90)
			(size 0.635 0.635)
			(layers "F.Cu" "F.Mask" "F.Paste")
			(net "GND")
		)
		(pad "87" smd circle
			(at 0.635 3.175 90)
			(size 0.635 0.635)
			(layers "F.Cu" "F.Mask" "F.Paste")
			(net "PCIE_B2T_B2_TX_DP<10>")
		)
		(pad "88" smd circle
			(at 0.635 4.445 90)
			(size 0.635 0.635)
			(layers "F.Cu" "F.Mask" "F.Paste")
			(net "GND")
		)
		(pad "89" smd circle
			(at 1.905 -4.445 90)
			(size 0.635 0.635)
			(layers "F.Cu" "F.Mask" "F.Paste")
			(net "PCIE_T2B_B2_RX_DN<2>")
		)
		(pad "90" smd circle
			(at 1.905 -3.175 90)
			(size 0.635 0.635)
			(layers "F.Cu" "F.Mask" "F.Paste")
			(net "GND")
		)
		(pad "91" smd circle
			(at 1.905 -1.905 90)
			(size 0.635 0.635)
			(layers "F.Cu" "F.Mask" "F.Paste")
			(net "PCIE_T2B_B2_RX_DN<10>")
		)
		(pad "92" smd circle
			(at 1.905 -0.635 90)
			(size 0.635 0.635)
			(layers "F.Cu" "F.Mask" "F.Paste")
			(net "GND")
		)
		(pad "93" smd circle
			(at 1.905 0.635 90)
			(size 0.635 0.635)
			(layers "F.Cu" "F.Mask" "F.Paste")
			(net "PCIE_B2T_B2_TX_DN<2>")
		)
		(pad "94" smd circle
			(at 1.905 1.905 90)
			(size 0.635 0.635)
			(layers "F.Cu" "F.Mask" "F.Paste")
			(net "GND")
		)
		(pad "95" smd circle
			(at 1.905 3.175 90)
			(size 0.635 0.635)
			(layers "F.Cu" "F.Mask" "F.Paste")
			(net "PCIE_B2T_B2_TX_DN<10>")
		)
		(pad "96" smd circle
			(at 1.905 4.445 90)
			(size 0.635 0.635)
			(layers "F.Cu" "F.Mask" "F.Paste")
			(net "GND")
		)
		(pad "97" smd circle
			(at 3.175 -4.445 90)
			(size 0.635 0.635)
			(layers "F.Cu" "F.Mask" "F.Paste")
			(net "GND")
		)
		(pad "98" smd circle
			(at 3.175 -3.175 90)
			(size 0.635 0.635)
			(layers "F.Cu" "F.Mask" "F.Paste")
			(net "PCIE_T2B_B2_RX_DP<1>")
		)
		(pad "99" smd circle
			(at 3.175 -1.905 90)
			(size 0.635 0.635)
			(layers "F.Cu" "F.Mask" "F.Paste")
			(net "GND")
		)
		(pad "100" smd circle
			(at 3.175 -0.635 90)
			(size 0.635 0.635)
			(layers "F.Cu" "F.Mask" "F.Paste")
			(net "PCIE_T2B_B2_RX_DP<9>")
		)
		(pad "101" smd circle
			(at 3.175 0.635 90)
			(size 0.635 0.635)
			(layers "F.Cu" "F.Mask" "F.Paste")
			(net "GND")
		)
		(pad "102" smd circle
			(at 3.175 1.905 90)
			(size 0.635 0.635)
			(layers "F.Cu" "F.Mask" "F.Paste")
			(net "PCIE_B2T_B2_TX_DP<1>")
		)
		(pad "103" smd circle
			(at 3.175 3.175 90)
			(size 0.635 0.635)
			(layers "F.Cu" "F.Mask" "F.Paste")
			(net "GND")
		)
		(pad "104" smd circle
			(at 3.175 4.445 90)
			(size 0.635 0.635)
			(layers "F.Cu" "F.Mask" "F.Paste")
			(net "PCIE_B2T_B2_TX_DP<9>")
		)
		(pad "105" smd circle
			(at 4.445 -4.445 90)
			(size 0.635 0.635)
			(layers "F.Cu" "F.Mask" "F.Paste")
			(net "GND")
		)
		(pad "106" smd circle
			(at 4.445 -3.175 90)
			(size 0.635 0.635)
			(layers "F.Cu" "F.Mask" "F.Paste")
			(net "PCIE_T2B_B2_RX_DN<1>")
		)
		(pad "107" smd circle
			(at 4.445 -1.905 90)
			(size 0.635 0.635)
			(layers "F.Cu" "F.Mask" "F.Paste")
			(net "GND")
		)
		(pad "108" smd circle
			(at 4.445 -0.635 90)
			(size 0.635 0.635)
			(layers "F.Cu" "F.Mask" "F.Paste")
			(net "PCIE_T2B_B2_RX_DN<9>")
		)
		(pad "109" smd circle
			(at 4.445 0.635 90)
			(size 0.635 0.635)
			(layers "F.Cu" "F.Mask" "F.Paste")
			(net "GND")
		)
		(pad "110" smd circle
			(at 4.445 1.905 90)
			(size 0.635 0.635)
			(layers "F.Cu" "F.Mask" "F.Paste")
			(net "PCIE_B2T_B2_TX_DN<1>")
		)
		(pad "111" smd circle
			(at 4.445 3.175 90)
			(size 0.635 0.635)
			(layers "F.Cu" "F.Mask" "F.Paste")
			(net "GND")
		)
		(pad "112" smd circle
			(at 4.445 4.445 90)
			(size 0.635 0.635)
			(layers "F.Cu" "F.Mask" "F.Paste")
			(net "PCIE_B2T_B2_TX_DN<9>")
		)
		(pad "113" smd circle
			(at 5.715 -4.445 90)
			(size 0.635 0.635)
			(layers "F.Cu" "F.Mask" "F.Paste")
			(net "PCIE_T2B_B2_RX_DP<0>")
		)
		(pad "114" smd circle
			(at 5.715 -3.175 90)
			(size 0.635 0.635)
			(layers "F.Cu" "F.Mask" "F.Paste")
			(net "GND")
		)
		(pad "115" smd circle
			(at 5.715 -1.905 90)
			(size 0.635 0.635)
			(layers "F.Cu" "F.Mask" "F.Paste")
			(net "PCIE_T2B_B2_RX_DP<8>")
		)
		(pad "116" smd circle
			(at 5.715 -0.635 90)
			(size 0.635 0.635)
			(layers "F.Cu" "F.Mask" "F.Paste")
			(net "GND")
		)
		(pad "117" smd circle
			(at 5.715 0.635 90)
			(size 0.635 0.635)
			(layers "F.Cu" "F.Mask" "F.Paste")
			(net "PCIE_B2T_B2_TX_DP<0>")
		)
		(pad "118" smd circle
			(at 5.715 1.905 90)
			(size 0.635 0.635)
			(layers "F.Cu" "F.Mask" "F.Paste")
			(net "GND")
		)
		(pad "119" smd circle
			(at 5.715 3.175 90)
			(size 0.635 0.635)
			(layers "F.Cu" "F.Mask" "F.Paste")
			(net "PCIE_B2T_B2_TX_DP<8>")
		)
	)
)
